(kicad_pcb
	(version 20260206)
	(generator "pcbnew")
	(generator_version "10.0")
	(general
		(thickness 1.6)
		(legacy_teardrops no)
	)
	(paper "A4")
	(title_block
		(title "panther-plus-userver — 13130-1b_20150205.brd")
		(comment 1 "Honey Badger (Wiwynn) / footprints 982-990 of 1509")
	)
	(layers
		(0 "F.Cu" signal "TOP")
		(4 "In1.Cu" signal "L2")
		(6 "In2.Cu" signal "L3")
		(8 "In3.Cu" signal "L4")
		(10 "In4.Cu" signal "L5")
		(12 "In5.Cu" signal "L6")
		(14 "In6.Cu" signal "L7")
		(16 "In7.Cu" signal "L8")
		(18 "In8.Cu" signal "L9")
		(20 "In9.Cu" signal "L10")
		(22 "In10.Cu" signal "L11")
		(2 "B.Cu" signal "BOTTOM")
		(9 "F.Adhes" user "F.Adhesive")
		(11 "B.Adhes" user "B.Adhesive")
		(13 "F.Paste" user "Package Geometry/Pastemask Top")
		(15 "B.Paste" user "Package Geometry/Pastemask Bottom")
		(5 "F.SilkS" user "Ref Des/Silkscreen Top")
		(7 "B.SilkS" user "Ref Des/Silkscreen Bottom")
		(1 "F.Mask" user "Board Geometry/Soldermask Top")
		(3 "B.Mask" user "Board Geometry/Soldermask Bottom")
		(17 "Dwgs.User" user "User.Drawings")
		(19 "Cmts.User" user "User.Comments")
		(21 "Eco1.User" user "User.Eco1")
		(23 "Eco2.User" user "User.Eco2")
		(25 "Edge.Cuts" user "Board Geometry/Outline")
		(27 "Margin" user)
		(31 "F.CrtYd" user "Package Geometry/Place Bound Top")
		(29 "B.CrtYd" user "Package Geometry/Place Bound Bottom")
		(35 "F.Fab" user "Ref Des/Assembly Top")
		(33 "B.Fab" user "Ref Des/Assembly Bottom")
	)
	(footprint ""
		(layer "B.Cu")
		(at 19.939 -64.77)
		(property "Reference" "PR21"
			(at 0 0 0)
			(layer "B.SilkS")
			(hide yes)
			(effects
				(font
					(size 1.27 1.27)
				)
				(justify mirror)
			)
		)
		(property "Value" "0R2J-2-GP"
			(at -1.7907 -1.1176 0)
			(unlocked yes)
			(layer "B.Fab")
			(hide yes)
			(effects
				(font
					(size 1.016 1.016)
					(thickness 0.1524)
				)
				(justify mirror)
			)
		)
		(property "Device Type" "R402H16"
			(at -1.7907 -2.6416 0)
			(unlocked yes)
			(layer "B.Fab")
			(hide yes)
			(effects
				(font
					(size 1.016 1.016)
					(thickness 0.1524)
				)
				(justify mirror)
			)
		)
		(duplicate_pad_numbers_are_jumpers no)
		(fp_rect
			(start 0.381 0.8382)
			(end -0.381 -0.8382)
			(stroke
				(width 0)
				(type default)
			)
			(fill no)
			(layer "B.CrtYd")
		)
		(fp_rect
			(start 0.381 0.8382)
			(end -0.381 -0.8382)
			(stroke
				(width 0)
				(type default)
			)
			(fill no)
			(layer "B.Fab")
		)
		(pad "1" smd custom
			(at 0 -0.4318 180)
			(size 0.127 0.127)
			(layers "B.Cu" "B.Mask" "B.Paste")
			(net "GND")
			(options
				(clearance outline)
				(anchor circle)
			)
			(primitives
				(gr_poly
					(pts
						(arc
							(start -0.2032 0.2794)
							(mid -0.239121 0.264521)
							(end -0.254 0.2286)
						)
						(arc
							(start -0.254 -0.2286)
							(mid -0.239121 -0.264521)
							(end -0.2032 -0.2794)
						)
						(arc
							(start 0.2032 -0.2794)
							(mid 0.239121 -0.264521)
							(end 0.254 -0.2286)
						)
						(arc
							(start 0.254 0.2286)
							(mid 0.239121 0.264521)
							(end 0.2032 0.2794)
						)
					)
					(width 0)
					(fill yes)
				)
			)
		)
		(pad "2" smd custom
			(at 0 0.4318 180)
			(size 0.127 0.127)
			(layers "B.Cu" "B.Mask" "B.Paste")
			(net "VR_PVNN_RTN")
			(options
				(clearance outline)
				(anchor circle)
			)
			(primitives
				(gr_poly
					(pts
						(arc
							(start -0.2032 0.2794)
							(mid -0.239121 0.264521)
							(end -0.254 0.2286)
						)
						(arc
							(start -0.254 -0.2286)
							(mid -0.239121 -0.264521)
							(end -0.2032 -0.2794)
						)
						(arc
							(start 0.2032 -0.2794)
							(mid 0.239121 -0.264521)
							(end 0.254 -0.2286)
						)
						(arc
							(start 0.254 0.2286)
							(mid 0.239121 0.264521)
							(end 0.2032 0.2794)
						)
					)
					(width 0)
					(fill yes)
				)
			)
		)
	)
	(footprint ""
		(layer "B.Cu")
		(at 197.358 -35.306 90)
		(property "Reference" "R497"
			(at 0 0 90)
			(layer "B.SilkS")
			(hide yes)
			(effects
				(font
					(size 1.27 1.27)
				)
				(justify mirror)
			)
		)
		(property "Value" "10KR2F-2-GP"
			(at -1.7907 -1.1176 90)
			(unlocked yes)
			(layer "B.Fab")
			(hide yes)
			(effects
				(font
					(size 1.016 1.016)
					(thickness 0.1524)
				)
				(justify mirror)
			)
		)
		(property "Device Type" "R402H16"
			(at -1.7907 -2.6416 90)
			(unlocked yes)
			(layer "B.Fab")
			(hide yes)
			(effects
				(font
					(size 1.016 1.016)
					(thickness 0.1524)
				)
				(justify mirror)
			)
		)
		(duplicate_pad_numbers_are_jumpers no)
		(fp_rect
			(start 0.381 0.8382)
			(end -0.381 -0.8382)
			(stroke
				(width 0)
				(type default)
			)
			(fill no)
			(layer "B.CrtYd")
		)
		(fp_rect
			(start 0.381 0.8382)
			(end -0.381 -0.8382)
			(stroke
				(width 0)
				(type default)
			)
			(fill no)
			(layer "B.Fab")
		)
		(pad "1" smd custom
			(at 0 -0.4318 270)
			(size 0.127 0.127)
			(layers "B.Cu" "B.Mask" "B.Paste")
			(net "VDDR_5VBIAS")
			(options
				(clearance outline)
				(anchor circle)
			)
			(primitives
				(gr_poly
					(pts
						(arc
							(start -0.2032 0.2794)
							(mid -0.239121 0.264521)
							(end -0.254 0.2286)
						)
						(arc
							(start -0.254 -0.2286)
							(mid -0.239121 -0.264521)
							(end -0.2032 -0.2794)
						)
						(arc
							(start 0.2032 -0.2794)
							(mid 0.239121 -0.264521)
							(end 0.254 -0.2286)
						)
						(arc
							(start 0.254 0.2286)
							(mid 0.239121 0.264521)
							(end 0.2032 0.2794)
						)
					)
					(width 0)
					(fill yes)
				)
			)
		)
		(pad "2" smd custom
			(at 0 0.4318 270)
			(size 0.127 0.127)
			(layers "B.Cu" "B.Mask" "B.Paste")
			(net "GND")
			(options
				(clearance outline)
				(anchor circle)
			)
			(primitives
				(gr_poly
					(pts
						(arc
							(start -0.2032 0.2794)
							(mid -0.239121 0.264521)
							(end -0.254 0.2286)
						)
						(arc
							(start -0.254 -0.2286)
							(mid -0.239121 -0.264521)
							(end -0.2032 -0.2794)
						)
						(arc
							(start 0.2032 -0.2794)
							(mid 0.239121 -0.264521)
							(end 0.254 -0.2286)
						)
						(arc
							(start 0.254 0.2286)
							(mid 0.239121 0.264521)
							(end 0.2032 0.2794)
						)
					)
					(width 0)
					(fill yes)
				)
			)
		)
	)
	(footprint ""
		(layer "B.Cu")
		(at 73.7108 -23.0124 90)
		(property "Reference" "PR172"
			(at 0 0 90)
			(layer "B.SilkS")
			(hide yes)
			(effects
				(font
					(size 1.27 1.27)
				)
				(justify mirror)
			)
		)
		(property "Value" "10KR2F-2-GP"
			(at -1.7907 -1.1176 90)
			(unlocked yes)
			(layer "B.Fab")
			(hide yes)
			(effects
				(font
					(size 1.016 1.016)
					(thickness 0.1524)
				)
				(justify mirror)
			)
		)
		(property "Device Type" "R402H16"
			(at -1.7907 -2.6416 90)
			(unlocked yes)
			(layer "B.Fab")
			(hide yes)
			(effects
				(font
					(size 1.016 1.016)
					(thickness 0.1524)
				)
				(justify mirror)
			)
		)
		(duplicate_pad_numbers_are_jumpers no)
		(fp_rect
			(start 0.381 0.8382)
			(end -0.381 -0.8382)
			(stroke
				(width 0)
				(type default)
			)
			(fill no)
			(layer "B.CrtYd")
		)
		(fp_rect
			(start 0.381 0.8382)
			(end -0.381 -0.8382)
			(stroke
				(width 0)
				(type default)
			)
			(fill no)
			(layer "B.Fab")
		)
		(pad "1" smd custom
			(at 0 -0.4318 270)
			(size 0.127 0.127)
			(layers "B.Cu" "B.Mask" "B.Paste")
			(net "P1V8_STBY_PG")
			(options
				(clearance outline)
				(anchor circle)
			)
			(primitives
				(gr_poly
					(pts
						(arc
							(start -0.2032 0.2794)
							(mid -0.239121 0.264521)
							(end -0.254 0.2286)
						)
						(arc
							(start -0.254 -0.2286)
							(mid -0.239121 -0.264521)
							(end -0.2032 -0.2794)
						)
						(arc
							(start 0.2032 -0.2794)
							(mid 0.239121 -0.264521)
							(end 0.254 -0.2286)
						)
						(arc
							(start 0.254 0.2286)
							(mid 0.239121 0.264521)
							(end 0.2032 0.2794)
						)
					)
					(width 0)
					(fill yes)
				)
			)
		)
		(pad "2" smd custom
			(at 0 0.4318 270)
			(size 0.127 0.127)
			(layers "B.Cu" "B.Mask" "B.Paste")
			(net "P3V3_STBY")
			(options
				(clearance outline)
				(anchor circle)
			)
			(primitives
				(gr_poly
					(pts
						(arc
							(start -0.2032 0.2794)
							(mid -0.239121 0.264521)
							(end -0.254 0.2286)
						)
						(arc
							(start -0.254 -0.2286)
							(mid -0.239121 -0.264521)
							(end -0.2032 -0.2794)
						)
						(arc
							(start 0.2032 -0.2794)
							(mid 0.239121 -0.264521)
							(end 0.254 -0.2286)
						)
						(arc
							(start 0.254 0.2286)
							(mid 0.239121 0.264521)
							(end 0.2032 0.2794)
						)
					)
					(width 0)
					(fill yes)
				)
			)
		)
	)
	(footprint ""
		(layer "B.Cu")
		(at 106.68 -52.705 180)
		(property "Reference" "C131"
			(at 0 0 0)
			(layer "B.SilkS")
			(hide yes)
			(effects
				(font
					(size 1.27 1.27)
				)
				(justify mirror)
			)
		)
		(property "Value" "SC1U10V2KX-1GP"
			(at -1.1811 -2.7051 180)
			(unlocked yes)
			(layer "B.Fab")
			(hide yes)
			(effects
				(font
					(size 1.016 1.016)
					(thickness 0.1524)
				)
				(justify mirror)
			)
		)
		(property "Device Type" "C402H22"
			(at -1.1811 -4.2291 180)
			(unlocked yes)
			(layer "B.Fab")
			(hide yes)
			(effects
				(font
					(size 1.016 1.016)
					(thickness 0.1524)
				)
				(justify mirror)
			)
		)
		(duplicate_pad_numbers_are_jumpers no)
		(fp_rect
			(start 0.381 0.7366)
			(end -0.381 -0.7366)
			(stroke
				(width 0)
				(type default)
			)
			(fill no)
			(layer "B.CrtYd")
		)
		(fp_rect
			(start 0.381 0.7366)
			(end -0.381 -0.7366)
			(stroke
				(width 0)
				(type default)
			)
			(fill no)
			(layer "B.Fab")
		)
		(pad "1" smd custom
			(at 0 -0.4572)
			(size 0.1143 0.1143)
			(layers "B.Cu" "B.Mask" "B.Paste")
			(net "PV_VDDR")
			(options
				(clearance outline)
				(anchor circle)
			)
			(primitives
				(gr_poly
					(pts
						(arc
							(start -0.254 0.1778)
							(mid -0.239121 0.213721)
							(end -0.2032 0.2286)
						)
						(arc
							(start 0.2032 0.2286)
							(mid 0.239121 0.213721)
							(end 0.254 0.1778)
						)
						(arc
							(start 0.254 -0.1778)
							(mid 0.239121 -0.213721)
							(end 0.2032 -0.2286)
						)
						(arc
							(start -0.2032 -0.2286)
							(mid -0.239121 -0.213721)
							(end -0.254 -0.1778)
						)
					)
					(width 0)
					(fill yes)
				)
			)
		)
		(pad "2" smd custom
			(at 0 0.4572)
			(size 0.1143 0.1143)
			(layers "B.Cu" "B.Mask" "B.Paste")
			(net "GND")
			(options
				(clearance outline)
				(anchor circle)
			)
			(primitives
				(gr_poly
					(pts
						(arc
							(start -0.254 0.1778)
							(mid -0.239121 0.213721)
							(end -0.2032 0.2286)
						)
						(arc
							(start 0.2032 0.2286)
							(mid 0.239121 0.213721)
							(end 0.254 0.1778)
						)
						(arc
							(start 0.254 -0.1778)
							(mid 0.239121 -0.213721)
							(end 0.2032 -0.2286)
						)
						(arc
							(start -0.2032 -0.2286)
							(mid -0.239121 -0.213721)
							(end -0.254 -0.1778)
						)
					)
					(width 0)
					(fill yes)
				)
			)
		)
	)
	(footprint ""
		(layer "B.Cu")
		(at 204.089 -30.861 90)
		(property "Reference" "C348"
			(at 0 0 90)
			(layer "B.SilkS")
			(hide yes)
			(effects
				(font
					(size 1.27 1.27)
				)
				(justify mirror)
			)
		)
		(property "Value" "SCD1U16V2KX-3GP"
			(at -1.8923 -1.2065 90)
			(unlocked yes)
			(layer "B.Fab")
			(hide yes)
			(effects
				(font
					(size 1.016 1.016)
					(thickness 0.1524)
				)
				(justify mirror)
			)
		)
		(property "Device Type" "C402H22"
			(at -1.8923 -2.7305 90)
			(unlocked yes)
			(layer "B.Fab")
			(hide yes)
			(effects
				(font
					(size 1.016 1.016)
					(thickness 0.1524)
				)
				(justify mirror)
			)
		)
		(duplicate_pad_numbers_are_jumpers no)
		(fp_rect
			(start 0.381 0.7366)
			(end -0.381 -0.7366)
			(stroke
				(width 0)
				(type default)
			)
			(fill no)
			(layer "B.CrtYd")
		)
		(fp_rect
			(start 0.381 0.7366)
			(end -0.381 -0.7366)
			(stroke
				(width 0)
				(type default)
			)
			(fill no)
			(layer "B.Fab")
		)
		(pad "1" smd custom
			(at 0 -0.4572 270)
			(size 0.1143 0.1143)
			(layers "B.Cu" "B.Mask" "B.Paste")
			(net "PV_VDDR")
			(options
				(clearance outline)
				(anchor circle)
			)
			(primitives
				(gr_poly
					(pts
						(arc
							(start -0.254 0.1778)
							(mid -0.239121 0.213721)
							(end -0.2032 0.2286)
						)
						(arc
							(start 0.2032 0.2286)
							(mid 0.239121 0.213721)
							(end 0.254 0.1778)
						)
						(arc
							(start 0.254 -0.1778)
							(mid 0.239121 -0.213721)
							(end 0.2032 -0.2286)
						)
						(arc
							(start -0.2032 -0.2286)
							(mid -0.239121 -0.213721)
							(end -0.254 -0.1778)
						)
					)
					(width 0)
					(fill yes)
				)
			)
		)
		(pad "2" smd custom
			(at 0 0.4572 270)
			(size 0.1143 0.1143)
			(layers "B.Cu" "B.Mask" "B.Paste")
			(net "GND")
			(options
				(clearance outline)
				(anchor circle)
			)
			(primitives
				(gr_poly
					(pts
						(arc
							(start -0.254 0.1778)
							(mid -0.239121 0.213721)
							(end -0.2032 0.2286)
						)
						(arc
							(start 0.2032 0.2286)
							(mid 0.239121 0.213721)
							(end 0.254 0.1778)
						)
						(arc
							(start 0.254 -0.1778)
							(mid 0.239121 -0.213721)
							(end 0.2032 -0.2286)
						)
						(arc
							(start -0.2032 -0.2286)
							(mid -0.239121 -0.213721)
							(end -0.254 -0.1778)
						)
					)
					(width 0)
					(fill yes)
				)
			)
		)
	)
	(footprint ""
		(layer "B.Cu")
		(at 199.300084 -68.799964 90)
		(property "Reference" "LED14"
			(at 0 0 90)
			(layer "B.SilkS")
			(hide yes)
			(effects
				(font
					(size 1.27 1.27)
				)
				(justify mirror)
			)
		)
		(property "Value" "LED-Y-11-GP"
			(at 0.0508 -2.6035 90)
			(unlocked yes)
			(layer "B.Fab")
			(hide yes)
			(effects
				(font
					(size 1.016 1.016)
					(thickness 0.1524)
				)
				(justify mirror)
			)
		)
		(property "Device Type" "19-21UBC-1"
			(at 0.0508 -4.1275 90)
			(unlocked yes)
			(layer "B.Fab")
			(hide yes)
			(effects
				(font
					(size 1.016 1.016)
					(thickness 0.1524)
				)
				(justify mirror)
			)
		)
		(duplicate_pad_numbers_are_jumpers no)
		(fp_line
			(start 0.5461 -1.3081)
			(end -0.5207 -1.3081)
			(stroke
				(width 0.254)
				(type default)
			)
			(layer "B.SilkS")
		)
		(fp_rect
			(start 0.6604 1.1811)
			(end -0.6604 -1.1811)
			(stroke
				(width 0)
				(type default)
			)
			(fill no)
			(layer "B.CrtYd")
		)
		(fp_rect
			(start 0.6604 1.1811)
			(end -0.6604 -1.1811)
			(stroke
				(width 0)
				(type default)
			)
			(fill no)
			(layer "B.Fab")
		)
		(pad "1" smd rect
			(at 0 -0.652526 270)
			(size 1.0668 0.8128)
			(layers "B.Cu" "B.Mask" "B.Paste")
			(net "BEEP_LED_D")
		)
		(pad "2" smd rect
			(at 0 0.652526 270)
			(size 1.0668 0.8128)
			(layers "B.Cu" "B.Mask" "B.Paste")
			(net "BEEP_LED")
		)
	)
	(footprint ""
		(layer "B.Cu")
		(at 201.2696 -34.1884 90)
		(property "Reference" "LED7"
			(at 0 0 90)
			(layer "B.SilkS")
			(hide yes)
			(effects
				(font
					(size 1.27 1.27)
				)
				(justify mirror)
			)
		)
		(property "Value" "LED-YG-51-GP"
			(at 0.0381 -2.6162 90)
			(unlocked yes)
			(layer "B.Fab")
			(hide yes)
			(effects
				(font
					(size 1.016 1.016)
					(thickness 0.1524)
				)
				(justify mirror)
			)
		)
		(property "Device Type" "LED1608AKH40"
			(at 0.0381 -4.1402 90)
			(unlocked yes)
			(layer "B.Fab")
			(hide yes)
			(effects
				(font
					(size 1.016 1.016)
					(thickness 0.1524)
				)
				(justify mirror)
			)
		)
		(duplicate_pad_numbers_are_jumpers no)
		(fp_line
			(start 0.5334 1.3081)
			(end -0.5334 1.3081)
			(stroke
				(width 0.254)
				(type default)
			)
			(layer "B.SilkS")
		)
		(fp_rect
			(start 0.6604 1.1811)
			(end -0.6604 -1.1811)
			(stroke
				(width 0)
				(type default)
			)
			(fill no)
			(layer "B.CrtYd")
		)
		(fp_rect
			(start 0.6604 1.1811)
			(end -0.6604 -1.1811)
			(stroke
				(width 0)
				(type default)
			)
			(fill no)
			(layer "B.Fab")
		)
		(pad "A" smd rect
			(at 0 -0.652526 270)
			(size 1.0668 0.8128)
			(layers "B.Cu" "B.Mask" "B.Paste")
			(net "PORT80_R_BIT2")
		)
		(pad "K" smd rect
			(at 0 0.652526 270)
			(size 1.0668 0.8128)
			(layers "B.Cu" "B.Mask" "B.Paste")
			(net "PORT80_BIT2")
		)
	)
	(footprint ""
		(layer "B.Cu")
		(at 35.687 -20.447)
		(property "Reference" "R451"
			(at 0 0 0)
			(layer "B.SilkS")
			(hide yes)
			(effects
				(font
					(size 1.27 1.27)
				)
				(justify mirror)
			)
		)
		(property "Value" "4K7R2F-GP"
			(at -1.7907 -1.1176 0)
			(unlocked yes)
			(layer "B.Fab")
			(hide yes)
			(effects
				(font
					(size 1.016 1.016)
					(thickness 0.1524)
				)
				(justify mirror)
			)
		)
		(property "Device Type" "R402H16"
			(at -1.7907 -2.6416 0)
			(unlocked yes)
			(layer "B.Fab")
			(hide yes)
			(effects
				(font
					(size 1.016 1.016)
					(thickness 0.1524)
				)
				(justify mirror)
			)
		)
		(duplicate_pad_numbers_are_jumpers no)
		(fp_rect
			(start 0.381 0.8382)
			(end -0.381 -0.8382)
			(stroke
				(width 0)
				(type default)
			)
			(fill no)
			(layer "B.CrtYd")
		)
		(fp_rect
			(start 0.381 0.8382)
			(end -0.381 -0.8382)
			(stroke
				(width 0)
				(type default)
			)
			(fill no)
			(layer "B.Fab")
		)
		(pad "1" smd custom
			(at 0 -0.4318 180)
			(size 0.127 0.127)
			(layers "B.Cu" "B.Mask" "B.Paste")
			(net "P3V3")
			(options
				(clearance outline)
				(anchor circle)
			)
			(primitives
				(gr_poly
					(pts
						(arc
							(start -0.2032 0.2794)
							(mid -0.239121 0.264521)
							(end -0.254 0.2286)
						)
						(arc
							(start -0.254 -0.2286)
							(mid -0.239121 -0.264521)
							(end -0.2032 -0.2794)
						)
						(arc
							(start 0.2032 -0.2794)
							(mid 0.239121 -0.264521)
							(end 0.254 -0.2286)
						)
						(arc
							(start 0.254 0.2286)
							(mid 0.239121 0.264521)
							(end 0.2032 0.2794)
						)
					)
					(width 0)
					(fill yes)
				)
			)
		)
		(pad "2" smd custom
			(at 0 0.4318 180)
			(size 0.127 0.127)
			(layers "B.Cu" "B.Mask" "B.Paste")
			(net "CLKBUFF_BYPASS_OR_PLL")
			(options
				(clearance outline)
				(anchor circle)
			)
			(primitives
				(gr_poly
					(pts
						(arc
							(start -0.2032 0.2794)
							(mid -0.239121 0.264521)
							(end -0.254 0.2286)
						)
						(arc
							(start -0.254 -0.2286)
							(mid -0.239121 -0.264521)
							(end -0.2032 -0.2794)
						)
						(arc
							(start 0.2032 -0.2794)
							(mid 0.239121 -0.264521)
							(end 0.254 -0.2286)
						)
						(arc
							(start 0.254 0.2286)
							(mid 0.239121 0.264521)
							(end 0.2032 0.2794)
						)
					)
					(width 0)
					(fill yes)
				)
			)
		)
	)
	(footprint ""
		(layer "B.Cu")
		(at 182.977028 -30.39999 -90)
		(property "Reference" "PR213"
			(at 0 0 90)
			(layer "B.SilkS")
			(hide yes)
			(effects
				(font
					(size 1.27 1.27)
				)
				(justify mirror)
			)
		)
		(property "Value" "249R2F-GP"
			(at -1.7907 -1.1176 270)
			(unlocked yes)
			(layer "B.Fab")
			(hide yes)
			(effects
				(font
					(size 1.016 1.016)
					(thickness 0.1524)
				)
				(justify mirror)
			)
		)
		(property "Device Type" "R402H16"
			(at -1.7907 -2.6416 270)
			(unlocked yes)
			(layer "B.Fab")
			(hide yes)
			(effects
				(font
					(size 1.016 1.016)
					(thickness 0.1524)
				)
				(justify mirror)
			)
		)
		(duplicate_pad_numbers_are_jumpers no)
		(fp_rect
			(start 0.381 0.8382)
			(end -0.381 -0.8382)
			(stroke
				(width 0)
				(type default)
			)
			(fill no)
			(layer "B.CrtYd")
		)
		(fp_rect
			(start 0.381 0.8382)
			(end -0.381 -0.8382)
			(stroke
				(width 0)
				(type default)
			)
			(fill no)
			(layer "B.Fab")
		)
		(pad "1" smd custom
			(at 0 -0.4318 90)
			(size 0.127 0.127)
			(layers "B.Cu" "B.Mask" "B.Paste")
			(net "VR_PVDDR_A_FB")
			(options
				(clearance outline)
				(anchor circle)
			)
			(primitives
				(gr_poly
					(pts
						(arc
							(start -0.2032 0.2794)
							(mid -0.239121 0.264521)
							(end -0.254 0.2286)
						)
						(arc
							(start -0.254 -0.2286)
							(mid -0.239121 -0.264521)
							(end -0.2032 -0.2794)
						)
						(arc
							(start 0.2032 -0.2794)
							(mid 0.239121 -0.264521)
							(end 0.254 -0.2286)
						)
						(arc
							(start 0.254 0.2286)
							(mid 0.239121 0.264521)
							(end 0.2032 0.2794)
						)
					)
					(width 0)
					(fill yes)
				)
			)
		)
		(pad "2" smd custom
			(at 0 0.4318 90)
			(size 0.127 0.127)
			(layers "B.Cu" "B.Mask" "B.Paste")
			(net "VSENSE_PVDDR_A_VSEN_FB")
			(options
				(clearance outline)
				(anchor circle)
			)
			(primitives
				(gr_poly
					(pts
						(arc
							(start -0.2032 0.2794)
							(mid -0.239121 0.264521)
							(end -0.254 0.2286)
						)
						(arc
							(start -0.254 -0.2286)
							(mid -0.239121 -0.264521)
							(end -0.2032 -0.2794)
						)
						(arc
							(start 0.2032 -0.2794)
							(mid 0.239121 -0.264521)
							(end 0.254 -0.2286)
						)
						(arc
							(start 0.254 0.2286)
							(mid 0.239121 0.264521)
							(end 0.2032 0.2794)
						)
					)
					(width 0)
					(fill yes)
				)
			)
		)
	)
)
